(kicad_pcb
	(version 20260206)
	(generator "pcbnew")
	(generator_version "10.0")
	(general
		(thickness 1.6)
		(legacy_teardrops no)
	)
	(paper "A4")
	(title_block
		(title "v1-chassis-manager — T6M_CM_d_v01_1031_1645.brd")
		(comment 1 "Open CloudServer (Microsoft) / footprints 495-503 of 2512")
	)
	(layers
		(0 "F.Cu" signal "TOP")
		(4 "In1.Cu" signal "GND1")
		(6 "In2.Cu" signal "IN1")
		(8 "In3.Cu" signal "VCC1")
		(10 "In4.Cu" signal "VCC2")
		(12 "In5.Cu" signal "GND2")
		(14 "In6.Cu" signal "IN2")
		(16 "In7.Cu" signal "IN3")
		(18 "In8.Cu" signal "GND3")
		(2 "B.Cu" signal "BOTTOM")
		(9 "F.Adhes" user "F.Adhesive")
		(11 "B.Adhes" user "B.Adhesive")
		(13 "F.Paste" user "Package Geometry/Pastemask Top")
		(15 "B.Paste" user "Package Geometry/Pastemask Bottom")
		(5 "F.SilkS" user "Ref Des/Silkscreen Top")
		(7 "B.SilkS" user "Ref Des/Silkscreen Bottom")
		(1 "F.Mask" user "Board Geometry/Soldermask Top")
		(3 "B.Mask" user "Board Geometry/Soldermask Bottom")
		(17 "Dwgs.User" user "User.Drawings")
		(19 "Cmts.User" user "User.Comments")
		(21 "Eco1.User" user "User.Eco1")
		(23 "Eco2.User" user "User.Eco2")
		(25 "Edge.Cuts" user "Board Geometry/Outline")
		(27 "Margin" user)
		(31 "F.CrtYd" user "Package Geometry/Place Bound Top")
		(29 "B.CrtYd" user "Package Geometry/Place Bound Bottom")
		(35 "F.Fab" user "Ref Des/Assembly Top")
		(33 "B.Fab" user "Ref Des/Assembly Bottom")
	)
	(footprint ""
		(layer "F.Cu")
		(at 132.5372 -54.1274 -90)
		(property "Reference" "R1326"
			(at -0.9652 -0.20447 90)
			(unlocked yes)
			(layer "F.SilkS")
			(effects
				(font
					(size 0.7874 0.5842)
					(thickness 0.1524)
				)
				(justify left)
			)
		)
		(property "Value" ""
			(at 0 0 270)
			(layer "F.Fab")
			(effects
				(font
					(size 1.27 1.27)
				)
			)
		)
		(duplicate_pad_numbers_are_jumpers no)
		(fp_line
			(start -0.7874 0.4064)
			(end -0.7874 -0.4064)
			(stroke
				(width 0.1524)
				(type default)
			)
			(layer "F.SilkS")
		)
		(fp_line
			(start 0.7874 0.4064)
			(end -0.7874 0.4064)
			(stroke
				(width 0.1524)
				(type default)
			)
			(layer "F.SilkS")
		)
		(fp_line
			(start -0.7874 -0.4064)
			(end 0.7874 -0.4064)
			(stroke
				(width 0.1524)
				(type default)
			)
			(layer "F.SilkS")
		)
		(fp_line
			(start 0.7874 -0.4064)
			(end 0.7874 0.4064)
			(stroke
				(width 0.1524)
				(type default)
			)
			(layer "F.SilkS")
		)
		(fp_poly
			(pts
				(xy -0.508 0.2794) (xy -0.508 0.2286) (xy -0.635 0.2286) (xy -0.635 -0.254) (xy -0.5334 -0.254)
				(xy -0.5334 -0.2794) (xy 0.5334 -0.2794) (xy 0.5334 -0.254) (xy 0.635 -0.254) (xy 0.635 0.254) (xy 0.5334 0.254)
				(xy 0.5334 0.2794)
			)
			(stroke
				(width 0)
				(type default)
			)
			(fill no)
			(layer "F.CrtYd")
		)
		(pad "1" smd rect
			(at 0.40005 0 270)
			(size 0.4572 0.508)
			(layers "F.Cu" "F.Mask" "F.Paste")
			(net "UART_RI_P4_R_N")
		)
		(pad "2" smd rect
			(at -0.40005 0 270)
			(size 0.4572 0.508)
			(layers "F.Cu" "F.Mask" "F.Paste")
			(net "GND")
		)
	)
	(footprint ""
		(layer "F.Cu")
		(at 60.04306 -106.237024 180)
		(property "Reference" "PC133"
			(at 1.961134 -4.863084 0)
			(unlocked yes)
			(layer "F.SilkS")
			(effects
				(font
					(size 0.7874 0.5842)
					(thickness 0.1524)
				)
				(justify left)
			)
		)
		(property "Value" ""
			(at 0 0 180)
			(layer "F.Fab")
			(effects
				(font
					(size 1.27 1.27)
				)
			)
		)
		(duplicate_pad_numbers_are_jumpers no)
		(fp_line
			(start 1.905 0.8636)
			(end -1.905 0.8636)
			(stroke
				(width 0.1524)
				(type default)
			)
			(layer "F.SilkS")
		)
		(fp_line
			(start 1.905 -0.8636)
			(end 1.905 0.8636)
			(stroke
				(width 0.1524)
				(type default)
			)
			(layer "F.SilkS")
		)
		(fp_line
			(start 0 0.8382)
			(end 0 -0.8382)
			(stroke
				(width 0.1524)
				(type default)
			)
			(layer "F.SilkS")
		)
		(fp_line
			(start -1.905 0.8636)
			(end -1.905 -0.8636)
			(stroke
				(width 0.1524)
				(type default)
			)
			(layer "F.SilkS")
		)
		(fp_line
			(start -1.905 -0.8636)
			(end 1.905 -0.8636)
			(stroke
				(width 0.1524)
				(type default)
			)
			(layer "F.SilkS")
		)
		(fp_rect
			(start -1.524 0.7366)
			(end 1.524 -0.7366)
			(stroke
				(width 0)
				(type default)
			)
			(fill no)
			(layer "F.CrtYd")
		)
		(pad "1" smd rect
			(at 0.94996 0 180)
			(size 1.1176 1.3716)
			(layers "F.Cu" "F.Mask" "F.Paste")
			(net "P3V3_STB_NODE1")
		)
		(pad "2" smd rect
			(at -0.94996 0 180)
			(size 1.1176 1.3716)
			(layers "F.Cu" "F.Mask" "F.Paste")
			(net "GND")
		)
	)
	(footprint ""
		(layer "F.Cu")
		(at 157.33776 -188.126624 90)
		(property "Reference" "R1220"
			(at 5.519674 -3.560572 90)
			(unlocked yes)
			(layer "F.SilkS")
			(effects
				(font
					(size 0.7874 0.5842)
					(thickness 0.1524)
				)
				(justify left)
			)
		)
		(property "Value" ""
			(at 0 0 90)
			(layer "F.Fab")
			(effects
				(font
					(size 1.27 1.27)
				)
			)
		)
		(duplicate_pad_numbers_are_jumpers no)
		(fp_line
			(start 0.7874 -0.4064)
			(end 0.7874 0.4064)
			(stroke
				(width 0.1524)
				(type default)
			)
			(layer "F.SilkS")
		)
		(fp_line
			(start -0.7874 -0.4064)
			(end 0.7874 -0.4064)
			(stroke
				(width 0.1524)
				(type default)
			)
			(layer "F.SilkS")
		)
		(fp_line
			(start 0.7874 0.4064)
			(end -0.7874 0.4064)
			(stroke
				(width 0.1524)
				(type default)
			)
			(layer "F.SilkS")
		)
		(fp_line
			(start -0.7874 0.4064)
			(end -0.7874 -0.4064)
			(stroke
				(width 0.1524)
				(type default)
			)
			(layer "F.SilkS")
		)
		(fp_poly
			(pts
				(xy -0.508 0.2794) (xy -0.508 0.2286) (xy -0.635 0.2286) (xy -0.635 -0.254) (xy -0.5334 -0.254)
				(xy -0.5334 -0.2794) (xy 0.5334 -0.2794) (xy 0.5334 -0.254) (xy 0.635 -0.254) (xy 0.635 0.254) (xy 0.5334 0.254)
				(xy 0.5334 0.2794)
			)
			(stroke
				(width 0)
				(type default)
			)
			(fill no)
			(layer "F.CrtYd")
		)
		(pad "1" smd rect
			(at 0.40005 0 90)
			(size 0.4572 0.508)
			(layers "F.Cu" "F.Mask" "F.Paste")
			(net "FAN2_TACH_R")
		)
		(pad "2" smd rect
			(at -0.40005 0 90)
			(size 0.4572 0.508)
			(layers "F.Cu" "F.Mask" "F.Paste")
			(net "GND")
		)
	)
	(footprint ""
		(layer "F.Cu")
		(at 12.930124 -130.120136 90)
		(property "Reference" "PR28"
			(at -2.068068 -1.078484 90)
			(unlocked yes)
			(layer "F.SilkS")
			(effects
				(font
					(size 0.7874 0.5842)
					(thickness 0.1524)
				)
				(justify left)
			)
		)
		(property "Value" ""
			(at 0 0 90)
			(layer "F.Fab")
			(effects
				(font
					(size 1.27 1.27)
				)
			)
		)
		(duplicate_pad_numbers_are_jumpers no)
		(fp_line
			(start 0.7874 -0.4064)
			(end 0.7874 0.4064)
			(stroke
				(width 0.1524)
				(type default)
			)
			(layer "F.SilkS")
		)
		(fp_line
			(start -0.7874 -0.4064)
			(end 0.7874 -0.4064)
			(stroke
				(width 0.1524)
				(type default)
			)
			(layer "F.SilkS")
		)
		(fp_line
			(start 0.7874 0.4064)
			(end -0.7874 0.4064)
			(stroke
				(width 0.1524)
				(type default)
			)
			(layer "F.SilkS")
		)
		(fp_line
			(start -0.7874 0.4064)
			(end -0.7874 -0.4064)
			(stroke
				(width 0.1524)
				(type default)
			)
			(layer "F.SilkS")
		)
		(fp_poly
			(pts
				(xy -0.508 0.2794) (xy -0.508 0.2286) (xy -0.635 0.2286) (xy -0.635 -0.254) (xy -0.5334 -0.254)
				(xy -0.5334 -0.2794) (xy 0.5334 -0.2794) (xy 0.5334 -0.254) (xy 0.635 -0.254) (xy 0.635 0.254) (xy 0.5334 0.254)
				(xy 0.5334 0.2794)
			)
			(stroke
				(width 0)
				(type default)
			)
			(fill no)
			(layer "F.CrtYd")
		)
		(pad "1" smd rect
			(at 0.40005 0 90)
			(size 0.4572 0.508)
			(layers "F.Cu" "F.Mask" "F.Paste")
			(net "P1V05_NODE1_TRIP")
		)
		(pad "2" smd rect
			(at -0.40005 0 90)
			(size 0.4572 0.508)
			(layers "F.Cu" "F.Mask" "F.Paste")
			(net "GND")
		)
	)
	(footprint ""
		(layer "F.Cu")
		(at 187.586366 -122.844814)
		(property "Reference" "R1034"
			(at 5.453634 19.112484 0)
			(unlocked yes)
			(layer "F.SilkS")
			(effects
				(font
					(size 0.7874 0.5842)
					(thickness 0.1524)
				)
				(justify left)
			)
		)
		(property "Value" ""
			(at 0 0 0)
			(layer "F.Fab")
			(effects
				(font
					(size 1.27 1.27)
				)
			)
		)
		(duplicate_pad_numbers_are_jumpers no)
		(fp_line
			(start -0.7874 -0.4064)
			(end 0.7874 -0.4064)
			(stroke
				(width 0.1524)
				(type default)
			)
			(layer "F.SilkS")
		)
		(fp_line
			(start -0.7874 0.4064)
			(end -0.7874 -0.4064)
			(stroke
				(width 0.1524)
				(type default)
			)
			(layer "F.SilkS")
		)
		(fp_line
			(start 0.7874 -0.4064)
			(end 0.7874 0.4064)
			(stroke
				(width 0.1524)
				(type default)
			)
			(layer "F.SilkS")
		)
		(fp_line
			(start 0.7874 0.4064)
			(end -0.7874 0.4064)
			(stroke
				(width 0.1524)
				(type default)
			)
			(layer "F.SilkS")
		)
		(fp_poly
			(pts
				(xy -0.508 0.2794) (xy -0.508 0.2286) (xy -0.635 0.2286) (xy -0.635 -0.254) (xy -0.5334 -0.254)
				(xy -0.5334 -0.2794) (xy 0.5334 -0.2794) (xy 0.5334 -0.254) (xy 0.635 -0.254) (xy 0.635 0.254) (xy 0.5334 0.254)
				(xy 0.5334 0.2794)
			)
			(stroke
				(width 0)
				(type default)
			)
			(fill no)
			(layer "F.CrtYd")
		)
		(pad "1" smd rect
			(at 0.40005 0)
			(size 0.4572 0.508)
			(layers "F.Cu" "F.Mask" "F.Paste")
			(net "P3V3_STB_NODE1")
		)
		(pad "2" smd rect
			(at -0.40005 0)
			(size 0.4572 0.508)
			(layers "F.Cu" "F.Mask" "F.Paste")
			(net "JTAG_CPLD1_TMS")
		)
	)
	(footprint ""
		(layer "F.Cu")
		(at 129.244344 -108.27766 180)
		(property "Reference" "Y1"
			(at 0.254 -2.310384 0)
			(unlocked yes)
			(layer "F.SilkS")
			(effects
				(font
					(size 0.7874 0.5842)
					(thickness 0.1524)
				)
				(justify left)
			)
		)
		(property "Value" ""
			(at 0 0 180)
			(layer "F.Fab")
			(effects
				(font
					(size 1.27 1.27)
				)
			)
		)
		(duplicate_pad_numbers_are_jumpers no)
		(fp_line
			(start 1.9558 1.6002)
			(end -1.9558 1.6002)
			(stroke
				(width 0.1524)
				(type default)
			)
			(layer "F.SilkS")
		)
		(fp_line
			(start 1.9558 -1.6002)
			(end 1.9558 1.6002)
			(stroke
				(width 0.1524)
				(type default)
			)
			(layer "F.SilkS")
		)
		(fp_line
			(start -1.524 0)
			(end -1.903984 0.1016)
			(stroke
				(width 0.1524)
				(type default)
			)
			(layer "F.SilkS")
		)
		(fp_line
			(start -1.903984 -0.1016)
			(end -1.524 0)
			(stroke
				(width 0.1524)
				(type default)
			)
			(layer "F.SilkS")
		)
		(fp_line
			(start -1.9558 1.6002)
			(end -1.9558 -1.6002)
			(stroke
				(width 0.1524)
				(type default)
			)
			(layer "F.SilkS")
		)
		(fp_line
			(start -1.9558 -1.6002)
			(end 1.9558 -1.6002)
			(stroke
				(width 0.1524)
				(type default)
			)
			(layer "F.SilkS")
		)
		(fp_poly
			(pts
				(xy -2.62255 0.354076) (xy -3.71475 -0.230124) (xy -3.71475 0.836676)
			)
			(stroke
				(width 0)
				(type default)
			)
			(fill yes)
			(layer "F.SilkS")
		)
		(fp_poly
			(pts
				(xy -0.3302 1.299972) (xy 0.3302 1.299972) (xy 0.3302 1.524) (xy 1.8796 1.524) (xy 1.8796 0.1778)
				(xy 1.649984 0.1778) (xy 1.649984 -0.1778) (xy 1.8796 -0.1778) (xy 1.8796 -1.524) (xy 0.3302 -1.524)
				(xy 0.3302 -1.299972) (xy -0.3302 -1.299972) (xy -0.3302 -1.524) (xy -1.8796 -1.524) (xy -1.8796 -0.1778)
				(xy -1.649984 -0.1778) (xy -1.649984 0.1778) (xy -1.8796 0.1778) (xy -1.8796 1.524) (xy -0.3302 1.524)
			)
			(stroke
				(width 0)
				(type default)
			)
			(fill no)
			(layer "F.CrtYd")
		)
		(fp_line
			(start 1.649984 1.299972)
			(end -1.649984 1.299972)
			(stroke
				(width 0.1)
				(type default)
			)
			(layer "F.Fab")
		)
		(fp_line
			(start 1.649984 -1.299972)
			(end 1.649984 1.299972)
			(stroke
				(width 0.1)
				(type default)
			)
			(layer "F.Fab")
		)
		(fp_line
			(start -1.649984 1.299972)
			(end -1.649984 -1.299972)
			(stroke
				(width 0.1)
				(type default)
			)
			(layer "F.Fab")
		)
		(fp_line
			(start -1.649984 -1.299972)
			(end 1.649984 -1.299972)
			(stroke
				(width 0.1)
				(type default)
			)
			(layer "F.Fab")
		)
		(fp_text user "3"
			(at 2.535174 -1.0033 0)
			(unlocked yes)
			(layer "F.SilkS")
			(effects
				(font
					(size 0.635 0.4064)
					(thickness 0.1524)
				)
				(justify left)
			)
		)
		(fp_text user "2"
			(at 2.4892 1.520952 0)
			(unlocked yes)
			(layer "F.SilkS")
			(effects
				(font
					(size 0.635 0.4064)
					(thickness 0.1524)
				)
				(justify left)
			)
		)
		(fp_text user "1"
			(at -2.028698 0.351028 0)
			(unlocked yes)
			(layer "F.SilkS")
			(effects
				(font
					(size 0.635 0.4064)
					(thickness 0.1524)
				)
				(justify left)
			)
		)
		(fp_text user "4"
			(at -2.227834 -1.448562 0)
			(unlocked yes)
			(layer "F.SilkS")
			(effects
				(font
					(size 0.635 0.4064)
					(thickness 0.1524)
				)
				(justify left)
			)
		)
		(pad "1" smd rect
			(at -1.100074 0.849884 270)
			(size 1.2192 1.4224)
			(layers "F.Cu" "F.Mask" "F.Paste")
			(net "XTAL_CLK_NODE1_X1")
		)
		(pad "2" smd rect
			(at 1.100074 0.849884 270)
			(size 1.2192 1.4224)
			(layers "F.Cu" "F.Mask" "F.Paste")
			(net "GND")
		)
		(pad "3" smd rect
			(at 1.100074 -0.849884 270)
			(size 1.2192 1.4224)
			(layers "F.Cu" "F.Mask" "F.Paste")
			(net "XTAL_CLK_NODE1_X2")
		)
		(pad "4" smd rect
			(at -1.100074 -0.849884 270)
			(size 1.2192 1.4224)
			(layers "F.Cu" "F.Mask" "F.Paste")
			(net "GND")
		)
	)
	(footprint ""
		(layer "F.Cu")
		(at 80.906874 -120.807226 180)
		(property "Reference" "C1120"
			(at 2.799334 -1.362964 0)
			(unlocked yes)
			(layer "F.SilkS")
			(effects
				(font
					(size 0.7874 0.5842)
					(thickness 0.1524)
				)
				(justify left)
			)
		)
		(property "Value" ""
			(at 0 0 180)
			(layer "F.Fab")
			(effects
				(font
					(size 1.27 1.27)
				)
			)
		)
		(duplicate_pad_numbers_are_jumpers no)
		(fp_line
			(start 0.7874 0.4064)
			(end -0.7874 0.4064)
			(stroke
				(width 0.1524)
				(type default)
			)
			(layer "F.SilkS")
		)
		(fp_line
			(start 0.7874 -0.4064)
			(end 0.7874 0.4064)
			(stroke
				(width 0.1524)
				(type default)
			)
			(layer "F.SilkS")
		)
		(fp_line
			(start 0 0.381)
			(end 0 -0.381)
			(stroke
				(width 0.1524)
				(type default)
			)
			(layer "F.SilkS")
		)
		(fp_line
			(start -0.7874 0.4064)
			(end -0.7874 -0.4064)
			(stroke
				(width 0.1524)
				(type default)
			)
			(layer "F.SilkS")
		)
		(fp_line
			(start -0.7874 -0.4064)
			(end 0.7874 -0.4064)
			(stroke
				(width 0.1524)
				(type default)
			)
			(layer "F.SilkS")
		)
		(fp_poly
			(pts
				(xy -0.5334 0.254) (xy -0.635 0.254) (xy -0.635 0.2286) (xy -0.635 -0.254) (xy -0.5334 -0.254) (xy -0.5334 -0.2794)
				(xy 0.5334 -0.2794) (xy 0.5334 -0.254) (xy 0.635 -0.254) (xy 0.635 0.254) (xy 0.5334 0.254) (xy 0.5334 0.2794)
				(xy -0.508 0.2794) (xy -0.5334 0.2794)
			)
			(stroke
				(width 0)
				(type default)
			)
			(fill no)
			(layer "F.CrtYd")
		)
		(pad "1" smd rect
			(at 0.40005 0 180)
			(size 0.4572 0.508)
			(layers "F.Cu" "F.Mask" "F.Paste")
			(net "GND")
		)
		(pad "2" smd rect
			(at -0.40005 0 180)
			(size 0.4572 0.508)
			(layers "F.Cu" "F.Mask" "F.Paste")
			(net "P3V3_NODE1")
		)
	)
	(footprint ""
		(layer "F.Cu")
		(at 106.170476 -166.848282 180)
		(property "Reference" "R767"
			(at -85.224366 -69.788278 0)
			(unlocked yes)
			(layer "F.SilkS")
			(effects
				(font
					(size 0.7874 0.5842)
					(thickness 0.1524)
				)
				(justify left)
			)
		)
		(property "Value" ""
			(at 0 0 180)
			(layer "F.Fab")
			(effects
				(font
					(size 1.27 1.27)
				)
			)
		)
		(duplicate_pad_numbers_are_jumpers no)
		(fp_line
			(start 0.7874 0.4064)
			(end -0.7874 0.4064)
			(stroke
				(width 0.1524)
				(type default)
			)
			(layer "F.SilkS")
		)
		(fp_line
			(start 0.7874 -0.4064)
			(end 0.7874 0.4064)
			(stroke
				(width 0.1524)
				(type default)
			)
			(layer "F.SilkS")
		)
		(fp_line
			(start -0.7874 0.4064)
			(end -0.7874 -0.4064)
			(stroke
				(width 0.1524)
				(type default)
			)
			(layer "F.SilkS")
		)
		(fp_line
			(start -0.7874 -0.4064)
			(end 0.7874 -0.4064)
			(stroke
				(width 0.1524)
				(type default)
			)
			(layer "F.SilkS")
		)
		(fp_poly
			(pts
				(xy -0.508 0.2794) (xy -0.508 0.2286) (xy -0.635 0.2286) (xy -0.635 -0.254) (xy -0.5334 -0.254)
				(xy -0.5334 -0.2794) (xy 0.5334 -0.2794) (xy 0.5334 -0.254) (xy 0.635 -0.254) (xy 0.635 0.254) (xy 0.5334 0.254)
				(xy 0.5334 0.2794)
			)
			(stroke
				(width 0)
				(type default)
			)
			(fill no)
			(layer "F.CrtYd")
		)
		(pad "1" smd rect
			(at 0.40005 0 180)
			(size 0.4572 0.508)
			(layers "F.Cu" "F.Mask" "F.Paste")
			(net "I2C_ALERT_FNACTRL2_N")
		)
		(pad "2" smd rect
			(at -0.40005 0 180)
			(size 0.4572 0.508)
			(layers "F.Cu" "F.Mask" "F.Paste")
			(net "P3V3_NODE1")
		)
	)
	(footprint ""
		(layer "F.Cu")
		(at 114.83721 -48.321976 -90)
		(property "Reference" "C484"
			(at 0.583946 1.016254 90)
			(unlocked yes)
			(layer "F.SilkS")
			(effects
				(font
					(size 0.7874 0.5842)
					(thickness 0.1524)
				)
				(justify left)
			)
		)
		(property "Value" ""
			(at 0 0 270)
			(layer "F.Fab")
			(effects
				(font
					(size 1.27 1.27)
				)
			)
		)
		(duplicate_pad_numbers_are_jumpers no)
		(fp_line
			(start -0.7874 0.4064)
			(end -0.7874 -0.4064)
			(stroke
				(width 0.1524)
				(type default)
			)
			(layer "F.SilkS")
		)
		(fp_line
			(start 0.7874 0.4064)
			(end -0.7874 0.4064)
			(stroke
				(width 0.1524)
				(type default)
			)
			(layer "F.SilkS")
		)
		(fp_line
			(start 0 0.381)
			(end 0 -0.381)
			(stroke
				(width 0.1524)
				(type default)
			)
			(layer "F.SilkS")
		)
		(fp_line
			(start -0.7874 -0.4064)
			(end 0.7874 -0.4064)
			(stroke
				(width 0.1524)
				(type default)
			)
			(layer "F.SilkS")
		)
		(fp_line
			(start 0.7874 -0.4064)
			(end 0.7874 0.4064)
			(stroke
				(width 0.1524)
				(type default)
			)
			(layer "F.SilkS")
		)
		(fp_poly
			(pts
				(xy -0.5334 0.254) (xy -0.635 0.254) (xy -0.635 0.2286) (xy -0.635 -0.254) (xy -0.5334 -0.254) (xy -0.5334 -0.2794)
				(xy 0.5334 -0.2794) (xy 0.5334 -0.254) (xy 0.635 -0.254) (xy 0.635 0.254) (xy 0.5334 0.254) (xy 0.5334 0.2794)
				(xy -0.508 0.2794) (xy -0.5334 0.2794)
			)
			(stroke
				(width 0)
				(type default)
			)
			(fill no)
			(layer "F.CrtYd")
		)
		(pad "1" smd rect
			(at 0.40005 0 270)
			(size 0.4572 0.508)
			(layers "F.Cu" "F.Mask" "F.Paste")
			(net "P3V3_NODE1")
		)
		(pad "2" smd rect
			(at -0.40005 0 270)
			(size 0.4572 0.508)
			(layers "F.Cu" "F.Mask" "F.Paste")
			(net "GND")
		)
	)
)
